# S9S_MB_2U (Grand Teton) — schematic netlist excerpt (pin names and nets, part order shuffled) for the footprints in the layout excerpt that follows; sources: Cadence DE-HDL packaged netlist, KiCad conversion of 03242023_DA0F0TMBIJ0_F0T_Motherboard_J_brd_V01_OCP.brd

R294  Q_RES  240 1% EMPTY  pkg 0402LF  page 119 : A = GND ; B = PD_CPU0_DMIMODE_OVERRIDE
PR373  Q_RES  1K 1% EMPTY  pkg 0402LF  page 278 : A = PVCCD_HV_CPU0_ISENSE_N ; B = GND

(kicad_pcb
	(version 20260206)
	(generator "pcbnew")
	(generator_version "10.0")
	(general
		(thickness 1.6)
		(legacy_teardrops no)
	)
	(paper "A4")
	(title_block
		(title "03242023_DA0F0TMBIJ0_F0T_Motherboard_J_brd_V01_OCP.brd")
		(comment 1 "Grand Teton / footprints 4982-4983 of 6105")
	)
	(layers
		(0 "F.Cu" signal "TOP")
		(4 "In1.Cu" signal "GND")
		(6 "In2.Cu" signal "IN1")
		(8 "In3.Cu" signal "GND1")
		(10 "In4.Cu" signal "IN2")
		(12 "In5.Cu" signal "GND2")
		(14 "In6.Cu" signal "IN3")
		(16 "In7.Cu" signal "GND3")
		(18 "In8.Cu" signal "VCC")
		(20 "In9.Cu" signal "VCC1")
		(22 "In10.Cu" signal "GND4")
		(24 "In11.Cu" signal "IN4")
		(26 "In12.Cu" signal "GND5")
		(28 "In13.Cu" signal "IN5")
		(30 "In14.Cu" signal "GND6")
		(32 "In15.Cu" signal "IN6")
		(34 "In16.Cu" signal "GND7")
		(2 "B.Cu" signal "BOTTOM")
		(9 "F.Adhes" user "F.Adhesive")
		(11 "B.Adhes" user "B.Adhesive")
		(13 "F.Paste" user "Package Geometry/Pastemask Top")
		(15 "B.Paste" user "Package Geometry/Pastemask Bottom")
		(5 "F.SilkS" user "Ref Des/Silkscreen Top")
		(7 "B.SilkS" user "Ref Des/Silkscreen Bottom")
		(1 "F.Mask" user "Board Geometry/Soldermask Top")
		(3 "B.Mask" user "Board Geometry/Soldermask Bottom")
		(17 "Dwgs.User" user "User.Drawings")
		(19 "Cmts.User" user "User.Comments")
		(21 "Eco1.User" user "User.Eco1")
		(23 "Eco2.User" user "User.Eco2")
		(25 "Edge.Cuts" user "Board Geometry/Outline")
		(27 "Margin" user)
		(31 "F.CrtYd" user "Package Geometry/Place Bound Top")
		(29 "B.CrtYd" user "Package Geometry/Place Bound Bottom")
		(35 "F.Fab" user "Ref Des/Assembly Top")
		(33 "B.Fab" user "Ref Des/Assembly Bottom")
	)
	(footprint ""
		(layer "B.Cu")
		(at 430.586388 -120.798082 180)
		(property "Reference" "PR373"
			(at 0 0 0)
			(layer "B.SilkS")
			(hide yes)
			(effects
				(font
					(size 1.27 1.27)
				)
				(justify mirror)
			)
		)
		(property "Value" ""
			(at 0 0 0)
			(layer "B.Fab")
			(effects
				(font
					(size 1.27 1.27)
				)
				(justify mirror)
			)
		)
		(duplicate_pad_numbers_are_jumpers no)
		(fp_line
			(start 0.7874 0.4064)
			(end 0.7874 -0.4064)
			(stroke
				(width 0.1524)
				(type default)
			)
			(layer "B.SilkS")
		)
		(fp_line
			(start 0.7874 -0.4064)
			(end -0.7874 -0.4064)
			(stroke
				(width 0.1524)
				(type default)
			)
			(layer "B.SilkS")
		)
		(fp_line
			(start -0.7874 0.4064)
			(end 0.7874 0.4064)
			(stroke
				(width 0.1524)
				(type default)
			)
			(layer "B.SilkS")
		)
		(fp_line
			(start -0.7874 -0.4064)
			(end -0.7874 0.4064)
			(stroke
				(width 0.1524)
				(type default)
			)
			(layer "B.SilkS")
		)
		(fp_line
			(start 0.67945 0.3048)
			(end 0.67945 -0.305054)
			(stroke
				(width 0.1)
				(type default)
			)
			(layer "B.Fab")
		)
		(fp_line
			(start 0.67945 -0.305054)
			(end 0.12065 -0.305054)
			(stroke
				(width 0.1)
				(type default)
			)
			(layer "B.Fab")
		)
		(fp_line
			(start 0.12065 0.3048)
			(end 0.67945 0.3048)
			(stroke
				(width 0.1)
				(type default)
			)
			(layer "B.Fab")
		)
		(fp_line
			(start 0.12065 0.2794)
			(end 0.12065 0.3048)
			(stroke
				(width 0.1)
				(type default)
			)
			(layer "B.Fab")
		)
		(fp_line
			(start 0.12065 -0.2794)
			(end -0.12065 -0.2794)
			(stroke
				(width 0.1)
				(type default)
			)
			(layer "B.Fab")
		)
		(fp_line
			(start 0.12065 -0.305054)
			(end 0.12065 -0.2794)
			(stroke
				(width 0.1)
				(type default)
			)
			(layer "B.Fab")
		)
		(fp_line
			(start -0.120396 0.3048)
			(end -0.120396 0.2794)
			(stroke
				(width 0.1)
				(type default)
			)
			(layer "B.Fab")
		)
		(fp_line
			(start -0.120396 0.2794)
			(end 0.12065 0.2794)
			(stroke
				(width 0.1)
				(type default)
			)
			(layer "B.Fab")
		)
		(fp_line
			(start -0.12065 -0.2794)
			(end -0.12065 -0.3048)
			(stroke
				(width 0.1)
				(type default)
			)
			(layer "B.Fab")
		)
		(fp_line
			(start -0.12065 -0.3048)
			(end -0.67945 -0.3048)
			(stroke
				(width 0.1)
				(type default)
			)
			(layer "B.Fab")
		)
		(fp_line
			(start -0.67945 0.3048)
			(end -0.120396 0.3048)
			(stroke
				(width 0.1)
				(type default)
			)
			(layer "B.Fab")
		)
		(fp_line
			(start -0.67945 -0.3048)
			(end -0.67945 0.3048)
			(stroke
				(width 0.1)
				(type default)
			)
			(layer "B.Fab")
		)
		(pad "1" smd circle
			(at 0.40005 0)
			(size 0 0)
			(layers "B.Cu" "B.Mask" "B.Paste")
			(net "PVCCD_HV_CPU0_ISENSE_N")
		)
		(pad "2" smd circle
			(at -0.40005 0)
			(size 0 0)
			(layers "B.Cu" "B.Mask" "B.Paste")
			(net "GND")
		)
	)
	(footprint ""
		(layer "B.Cu")
		(at 328.913998 -190.74511 -90)
		(property "Reference" "R294"
			(at 0 0 90)
			(layer "B.SilkS")
			(hide yes)
			(effects
				(font
					(size 1.27 1.27)
				)
				(justify mirror)
			)
		)
		(property "Value" ""
			(at 0 0 90)
			(layer "B.Fab")
			(effects
				(font
					(size 1.27 1.27)
				)
				(justify mirror)
			)
		)
		(duplicate_pad_numbers_are_jumpers no)
		(fp_line
			(start -0.7874 0.4064)
			(end 0.7874 0.4064)
			(stroke
				(width 0.1524)
				(type default)
			)
			(layer "B.SilkS")
		)
		(fp_line
			(start 0.7874 0.4064)
			(end 0.7874 -0.4064)
			(stroke
				(width 0.1524)
				(type default)
			)
			(layer "B.SilkS")
		)
		(fp_line
			(start -0.7874 -0.4064)
			(end -0.7874 0.4064)
			(stroke
				(width 0.1524)
				(type default)
			)
			(layer "B.SilkS")
		)
		(fp_line
			(start 0.7874 -0.4064)
			(end -0.7874 -0.4064)
			(stroke
				(width 0.1524)
				(type default)
			)
			(layer "B.SilkS")
		)
		(fp_line
			(start -0.67945 0.3048)
			(end -0.120396 0.3048)
			(stroke
				(width 0.1)
				(type default)
			)
			(layer "B.Fab")
		)
		(fp_line
			(start -0.120396 0.3048)
			(end -0.120396 0.2794)
			(stroke
				(width 0.1)
				(type default)
			)
			(layer "B.Fab")
		)
		(fp_line
			(start 0.12065 0.3048)
			(end 0.67945 0.3048)
			(stroke
				(width 0.1)
				(type default)
			)
			(layer "B.Fab")
		)
		(fp_line
			(start 0.67945 0.3048)
			(end 0.67945 -0.305054)
			(stroke
				(width 0.1)
				(type default)
			)
			(layer "B.Fab")
		)
		(fp_line
			(start -0.120396 0.2794)
			(end 0.12065 0.2794)
			(stroke
				(width 0.1)
				(type default)
			)
			(layer "B.Fab")
		)
		(fp_line
			(start 0.12065 0.2794)
			(end 0.12065 0.3048)
			(stroke
				(width 0.1)
				(type default)
			)
			(layer "B.Fab")
		)
		(fp_line
			(start -0.12065 -0.2794)
			(end -0.12065 -0.3048)
			(stroke
				(width 0.1)
				(type default)
			)
			(layer "B.Fab")
		)
		(fp_line
			(start 0.12065 -0.2794)
			(end -0.12065 -0.2794)
			(stroke
				(width 0.1)
				(type default)
			)
			(layer "B.Fab")
		)
		(fp_line
			(start -0.67945 -0.3048)
			(end -0.67945 0.3048)
			(stroke
				(width 0.1)
				(type default)
			)
			(layer "B.Fab")
		)
		(fp_line
			(start -0.12065 -0.3048)
			(end -0.67945 -0.3048)
			(stroke
				(width 0.1)
				(type default)
			)
			(layer "B.Fab")
		)
		(fp_line
			(start 0.12065 -0.305054)
			(end 0.12065 -0.2794)
			(stroke
				(width 0.1)
				(type default)
			)
			(layer "B.Fab")
		)
		(fp_line
			(start 0.67945 -0.305054)
			(end 0.12065 -0.305054)
			(stroke
				(width 0.1)
				(type default)
			)
			(layer "B.Fab")
		)
		(pad "1" smd circle
			(at 0.40005 0 90)
			(size 0 0)
			(layers "B.Cu" "B.Mask" "B.Paste")
			(net "GND")
		)
		(pad "2" smd circle
			(at -0.40005 0 90)
			(size 0 0)
			(layers "B.Cu" "B.Mask" "B.Paste")
			(net "PD_CPU0_DMIMODE_OVERRIDE")
		)
	)
)
